# S9S_MB_2U (Grand Teton) — schematic netlist excerpt (pin names and nets, part order shuffled) for the footprints in the layout excerpt that follows; sources: Cadence DE-HDL packaged netlist, KiCad conversion of 03242023_DA0F0TMBIJ0_F0T_Motherboard_J_brd_V01_OCP.brd

C1321  Q_CAP  0.1UF 25V 10% X7R  pkg 0402  page 239 : A = P3V3_AUX ; B = GND
PC113  Q_CAP  1UF 25V 10% X6S  pkg C0402  page 262 : A = P1V05_PCH_AUX_VCC ; B = GND

(kicad_pcb
	(version 20260206)
	(generator "pcbnew")
	(generator_version "10.0")
	(general
		(thickness 1.6)
		(legacy_teardrops no)
	)
	(paper "A4")
	(title_block
		(title "03242023_DA0F0TMBIJ0_F0T_Motherboard_J_brd_V01_OCP.brd")
		(comment 1 "Grand Teton / footprints 3454-3455 of 6105")
	)
	(layers
		(0 "F.Cu" signal "TOP")
		(4 "In1.Cu" signal "GND")
		(6 "In2.Cu" signal "IN1")
		(8 "In3.Cu" signal "GND1")
		(10 "In4.Cu" signal "IN2")
		(12 "In5.Cu" signal "GND2")
		(14 "In6.Cu" signal "IN3")
		(16 "In7.Cu" signal "GND3")
		(18 "In8.Cu" signal "VCC")
		(20 "In9.Cu" signal "VCC1")
		(22 "In10.Cu" signal "GND4")
		(24 "In11.Cu" signal "IN4")
		(26 "In12.Cu" signal "GND5")
		(28 "In13.Cu" signal "IN5")
		(30 "In14.Cu" signal "GND6")
		(32 "In15.Cu" signal "IN6")
		(34 "In16.Cu" signal "GND7")
		(2 "B.Cu" signal "BOTTOM")
		(9 "F.Adhes" user "F.Adhesive")
		(11 "B.Adhes" user "B.Adhesive")
		(13 "F.Paste" user "Package Geometry/Pastemask Top")
		(15 "B.Paste" user "Package Geometry/Pastemask Bottom")
		(5 "F.SilkS" user "Ref Des/Silkscreen Top")
		(7 "B.SilkS" user "Ref Des/Silkscreen Bottom")
		(1 "F.Mask" user "Board Geometry/Soldermask Top")
		(3 "B.Mask" user "Board Geometry/Soldermask Bottom")
		(17 "Dwgs.User" user "User.Drawings")
		(19 "Cmts.User" user "User.Comments")
		(21 "Eco1.User" user "User.Eco1")
		(23 "Eco2.User" user "User.Eco2")
		(25 "Edge.Cuts" user "Board Geometry/Outline")
		(27 "Margin" user)
		(31 "F.CrtYd" user "Package Geometry/Place Bound Top")
		(29 "B.CrtYd" user "Package Geometry/Place Bound Bottom")
		(35 "F.Fab" user "Ref Des/Assembly Top")
		(33 "B.Fab" user "Ref Des/Assembly Bottom")
	)
	(footprint ""
		(layer "F.Cu")
		(at 263.101582 -68.139056 180)
		(property "Reference" "PC113"
			(at 0 0 180)
			(layer "F.SilkS")
			(hide yes)
			(effects
				(font
					(size 1.27 1.27)
				)
			)
		)
		(property "Value" ""
			(at 0 0 180)
			(layer "F.Fab")
			(effects
				(font
					(size 1.27 1.27)
				)
			)
		)
		(duplicate_pad_numbers_are_jumpers no)
		(fp_line
			(start 0.7874 0.4064)
			(end -0.7874 0.4064)
			(stroke
				(width 0.1524)
				(type default)
			)
			(layer "F.SilkS")
		)
		(fp_line
			(start 0.7874 -0.4064)
			(end 0.7874 0.4064)
			(stroke
				(width 0.1524)
				(type default)
			)
			(layer "F.SilkS")
		)
		(fp_line
			(start -0.7874 0.4064)
			(end -0.7874 -0.4064)
			(stroke
				(width 0.1524)
				(type default)
			)
			(layer "F.SilkS")
		)
		(fp_line
			(start -0.7874 -0.4064)
			(end 0.7874 -0.4064)
			(stroke
				(width 0.1524)
				(type default)
			)
			(layer "F.SilkS")
		)
		(fp_line
			(start 0.67945 0.3048)
			(end 0.120396 0.3048)
			(stroke
				(width 0.1)
				(type default)
			)
			(layer "F.Fab")
		)
		(fp_line
			(start 0.67945 -0.3048)
			(end 0.67945 0.3048)
			(stroke
				(width 0.1)
				(type default)
			)
			(layer "F.Fab")
		)
		(fp_line
			(start 0.12065 -0.2794)
			(end 0.12065 -0.3048)
			(stroke
				(width 0.1)
				(type default)
			)
			(layer "F.Fab")
		)
		(fp_line
			(start 0.12065 -0.3048)
			(end 0.67945 -0.3048)
			(stroke
				(width 0.1)
				(type default)
			)
			(layer "F.Fab")
		)
		(fp_line
			(start 0.120396 0.3048)
			(end 0.120396 0.2794)
			(stroke
				(width 0.1)
				(type default)
			)
			(layer "F.Fab")
		)
		(fp_line
			(start 0.120396 0.2794)
			(end -0.12065 0.2794)
			(stroke
				(width 0.1)
				(type default)
			)
			(layer "F.Fab")
		)
		(fp_line
			(start -0.12065 0.3048)
			(end -0.67945 0.3048)
			(stroke
				(width 0.1)
				(type default)
			)
			(layer "F.Fab")
		)
		(fp_line
			(start -0.12065 0.2794)
			(end -0.12065 0.3048)
			(stroke
				(width 0.1)
				(type default)
			)
			(layer "F.Fab")
		)
		(fp_line
			(start -0.12065 -0.2794)
			(end 0.12065 -0.2794)
			(stroke
				(width 0.1)
				(type default)
			)
			(layer "F.Fab")
		)
		(fp_line
			(start -0.12065 -0.305054)
			(end -0.12065 -0.2794)
			(stroke
				(width 0.1)
				(type default)
			)
			(layer "F.Fab")
		)
		(fp_line
			(start -0.67945 0.3048)
			(end -0.67945 -0.305054)
			(stroke
				(width 0.1)
				(type default)
			)
			(layer "F.Fab")
		)
		(fp_line
			(start -0.67945 -0.305054)
			(end -0.12065 -0.305054)
			(stroke
				(width 0.1)
				(type default)
			)
			(layer "F.Fab")
		)
		(pad "1" smd circle
			(at -0.40005 0 180)
			(size 0 0)
			(layers "F.Cu" "F.Mask" "F.Paste")
			(net "P1V05_PCH_AUX_VCC")
		)
		(pad "2" smd circle
			(at 0.40005 0 180)
			(size 0 0)
			(layers "F.Cu" "F.Mask" "F.Paste")
			(net "GND")
		)
	)
	(footprint ""
		(layer "F.Cu")
		(at 118.804944 -75.031092 -90)
		(property "Reference" "C1321"
			(at 0 0 270)
			(layer "F.SilkS")
			(hide yes)
			(effects
				(font
					(size 1.27 1.27)
				)
			)
		)
		(property "Value" ""
			(at 0 0 270)
			(layer "F.Fab")
			(effects
				(font
					(size 1.27 1.27)
				)
			)
		)
		(duplicate_pad_numbers_are_jumpers no)
		(fp_line
			(start -0.7874 0.4064)
			(end -0.7874 -0.4064)
			(stroke
				(width 0.1524)
				(type default)
			)
			(layer "F.SilkS")
		)
		(fp_line
			(start 0.7874 0.4064)
			(end -0.7874 0.4064)
			(stroke
				(width 0.1524)
				(type default)
			)
			(layer "F.SilkS")
		)
		(fp_line
			(start -0.7874 -0.4064)
			(end 0.7874 -0.4064)
			(stroke
				(width 0.1524)
				(type default)
			)
			(layer "F.SilkS")
		)
		(fp_line
			(start 0.7874 -0.4064)
			(end 0.7874 0.4064)
			(stroke
				(width 0.1524)
				(type default)
			)
			(layer "F.SilkS")
		)
		(fp_line
			(start -0.67945 0.3048)
			(end -0.67945 -0.305054)
			(stroke
				(width 0.1)
				(type default)
			)
			(layer "F.Fab")
		)
		(fp_line
			(start -0.12065 0.3048)
			(end -0.67945 0.3048)
			(stroke
				(width 0.1)
				(type default)
			)
			(layer "F.Fab")
		)
		(fp_line
			(start 0.120396 0.3048)
			(end 0.120396 0.2794)
			(stroke
				(width 0.1)
				(type default)
			)
			(layer "F.Fab")
		)
		(fp_line
			(start 0.67945 0.3048)
			(end 0.120396 0.3048)
			(stroke
				(width 0.1)
				(type default)
			)
			(layer "F.Fab")
		)
		(fp_line
			(start -0.12065 0.2794)
			(end -0.12065 0.3048)
			(stroke
				(width 0.1)
				(type default)
			)
			(layer "F.Fab")
		)
		(fp_line
			(start 0.120396 0.2794)
			(end -0.12065 0.2794)
			(stroke
				(width 0.1)
				(type default)
			)
			(layer "F.Fab")
		)
		(fp_line
			(start -0.12065 -0.2794)
			(end 0.12065 -0.2794)
			(stroke
				(width 0.1)
				(type default)
			)
			(layer "F.Fab")
		)
		(fp_line
			(start 0.12065 -0.2794)
			(end 0.12065 -0.3048)
			(stroke
				(width 0.1)
				(type default)
			)
			(layer "F.Fab")
		)
		(fp_line
			(start 0.12065 -0.3048)
			(end 0.67945 -0.3048)
			(stroke
				(width 0.1)
				(type default)
			)
			(layer "F.Fab")
		)
		(fp_line
			(start 0.67945 -0.3048)
			(end 0.67945 0.3048)
			(stroke
				(width 0.1)
				(type default)
			)
			(layer "F.Fab")
		)
		(fp_line
			(start -0.67945 -0.305054)
			(end -0.12065 -0.305054)
			(stroke
				(width 0.1)
				(type default)
			)
			(layer "F.Fab")
		)
		(fp_line
			(start -0.12065 -0.305054)
			(end -0.12065 -0.2794)
			(stroke
				(width 0.1)
				(type default)
			)
			(layer "F.Fab")
		)
		(pad "1" smd circle
			(at -0.40005 0 270)
			(size 0 0)
			(layers "F.Cu" "F.Mask" "F.Paste")
			(net "P3V3_AUX")
		)
		(pad "2" smd circle
			(at 0.40005 0 270)
			(size 0 0)
			(layers "F.Cu" "F.Mask" "F.Paste")
			(net "GND")
		)
	)
)
